(kicad_pcb
	(version 20260206)
	(generator "pcbnew")
	(generator_version "10.0")
	(general
		(thickness 1.6)
		(legacy_teardrops no)
	)
	(paper "A4")
	(title_block
		(title "04192023_DAF0TMB3IC0_F0TG_MB_C_brd_V02_OCP.brd")
		(comment 1 "Grand Teton / footprints 3652-3657 of 8354")
	)
	(layers
		(0 "F.Cu" signal "TOP")
		(4 "In1.Cu" signal "GND")
		(6 "In2.Cu" signal "IN1")
		(8 "In3.Cu" signal "GND1")
		(10 "In4.Cu" signal "IN2")
		(12 "In5.Cu" signal "GND2")
		(14 "In6.Cu" signal "IN3")
		(16 "In7.Cu" signal "GND3")
		(18 "In8.Cu" signal "VCC")
		(20 "In9.Cu" signal "VCC1")
		(22 "In10.Cu" signal "GND4")
		(24 "In11.Cu" signal "IN4")
		(26 "In12.Cu" signal "GND5")
		(28 "In13.Cu" signal "IN5")
		(30 "In14.Cu" signal "GND6")
		(32 "In15.Cu" signal "IN6")
		(34 "In16.Cu" signal "GND7")
		(2 "B.Cu" signal "BOTTOM")
		(9 "F.Adhes" user "F.Adhesive")
		(11 "B.Adhes" user "B.Adhesive")
		(13 "F.Paste" user "Package Geometry/Pastemask Top")
		(15 "B.Paste" user "Package Geometry/Pastemask Bottom")
		(5 "F.SilkS" user "Ref Des/Silkscreen Top")
		(7 "B.SilkS" user "Ref Des/Silkscreen Bottom")
		(1 "F.Mask" user "Board Geometry/Soldermask Top")
		(3 "B.Mask" user "Board Geometry/Soldermask Bottom")
		(17 "Dwgs.User" user "User.Drawings")
		(19 "Cmts.User" user "User.Comments")
		(21 "Eco1.User" user "User.Eco1")
		(23 "Eco2.User" user "User.Eco2")
		(25 "Edge.Cuts" user "Board Geometry/Outline")
		(27 "Margin" user)
		(31 "F.CrtYd" user "Package Geometry/Place Bound Top")
		(29 "B.CrtYd" user "Package Geometry/Place Bound Bottom")
		(35 "F.Fab" user "Ref Des/Assembly Top")
		(33 "B.Fab" user "Ref Des/Assembly Bottom")
	)
	(footprint ""
		(layer "F.Cu")
		(at 304.293778 -434.264308 180)
		(property "Reference" "Q104"
			(at 4.643374 -1.833372 0)
			(unlocked yes)
			(layer "F.SilkS")
			(effects
				(font
					(size 0.7874 0.5842)
					(thickness 0.1524)
				)
				(justify left)
			)
		)
		(property "Value" ""
			(at 0 0 180)
			(layer "F.Fab")
			(effects
				(font
					(size 1.27 1.27)
				)
			)
		)
		(duplicate_pad_numbers_are_jumpers no)
		(fp_line
			(start 1.332738 1.100074)
			(end -1.332738 1.100074)
			(stroke
				(width 0.1524)
				(type default)
			)
			(layer "F.SilkS")
		)
		(fp_line
			(start 1.332738 -1.100074)
			(end 1.332738 1.100074)
			(stroke
				(width 0.1524)
				(type default)
			)
			(layer "F.SilkS")
		)
		(fp_line
			(start 0.4826 -1.100074)
			(end 1.332738 -1.100074)
			(stroke
				(width 0.1524)
				(type default)
			)
			(layer "F.SilkS")
		)
		(fp_line
			(start 0 -0.541274)
			(end 0.4826 -1.100074)
			(stroke
				(width 0.1524)
				(type default)
			)
			(layer "F.SilkS")
		)
		(fp_line
			(start -0.4826 -1.100074)
			(end 0 -0.541274)
			(stroke
				(width 0.1524)
				(type default)
			)
			(layer "F.SilkS")
		)
		(fp_line
			(start -1.332738 1.100074)
			(end -1.332738 -1.100074)
			(stroke
				(width 0.1524)
				(type default)
			)
			(layer "F.SilkS")
		)
		(fp_line
			(start -1.332738 -1.100074)
			(end -0.4826 -1.100074)
			(stroke
				(width 0.1524)
				(type default)
			)
			(layer "F.SilkS")
		)
		(fp_poly
			(pts
				(xy -1.489456 -1.189482) (xy -2.23393 -1.43764) (xy -1.737614 -1.933956)
			)
			(stroke
				(width 0)
				(type default)
			)
			(fill yes)
			(layer "F.SilkS")
		)
		(fp_line
			(start 0.674878 1.100074)
			(end -0.674878 1.100074)
			(stroke
				(width 0.1)
				(type default)
			)
			(layer "F.Fab")
		)
		(fp_line
			(start 0.674878 -1.100074)
			(end 0.674878 1.100074)
			(stroke
				(width 0.1)
				(type default)
			)
			(layer "F.Fab")
		)
		(fp_line
			(start -0.674878 1.100074)
			(end -0.674878 -1.100074)
			(stroke
				(width 0.1)
				(type default)
			)
			(layer "F.Fab")
		)
		(fp_line
			(start -0.674878 -1.100074)
			(end 0.674878 -1.100074)
			(stroke
				(width 0.1)
				(type default)
			)
			(layer "F.Fab")
		)
		(fp_poly
			(pts
				(xy -2.2352 -0.298958) (xy -2.2352 -1.001014) (xy -1.533144 -0.649986)
			)
			(stroke
				(width 0)
				(type default)
			)
			(fill yes)
			(layer "F.Fab")
		)
		(pad "1" smd rect
			(at -0.94996 -0.649986 270)
			(size 0.4318 0.508)
			(layers "F.Cu" "F.Mask" "F.Paste")
			(net "GND")
		)
		(pad "2" smd rect
			(at -0.94996 0 270)
			(size 0.4318 0.508)
			(layers "F.Cu" "F.Mask" "F.Paste")
			(net "GPU_FPGA_OVERT_N")
		)
		(pad "3" smd rect
			(at -0.94996 0.649986 270)
			(size 0.4318 0.508)
			(layers "F.Cu" "F.Mask" "F.Paste")
			(net "GPU_FPGA_OVERT_ISO_N")
		)
		(pad "4" smd rect
			(at 0.94996 0.649986 270)
			(size 0.4318 0.508)
			(layers "F.Cu" "F.Mask" "F.Paste")
			(net "GND")
		)
		(pad "5" smd rect
			(at 0.94996 0 270)
			(size 0.4318 0.508)
			(layers "F.Cu" "F.Mask" "F.Paste")
			(net "GPU_FPGA_OVERT")
		)
		(pad "6" smd rect
			(at 0.94996 -0.649986 270)
			(size 0.4318 0.508)
			(layers "F.Cu" "F.Mask" "F.Paste")
			(net "GPU_FPGA_OVERT")
		)
	)
	(footprint ""
		(layer "F.Cu")
		(at 102.154736 -123.64339 -90)
		(property "Reference" "Q18"
			(at -0.190754 1.882394 90)
			(unlocked yes)
			(layer "F.SilkS")
			(effects
				(font
					(size 0.7874 0.5842)
					(thickness 0.1524)
				)
			)
		)
		(property "Value" ""
			(at 0 0 270)
			(layer "F.Fab")
			(effects
				(font
					(size 1.27 1.27)
				)
			)
		)
		(duplicate_pad_numbers_are_jumpers no)
		(fp_line
			(start -1.7018 1.100074)
			(end -1.7018 -1.100074)
			(stroke
				(width 0.1524)
				(type default)
			)
			(layer "F.SilkS")
		)
		(fp_line
			(start 1.7018 1.100074)
			(end -1.7018 1.100074)
			(stroke
				(width 0.1524)
				(type default)
			)
			(layer "F.SilkS")
		)
		(fp_line
			(start -1.7018 -1.100074)
			(end 1.7018 -1.100074)
			(stroke
				(width 0.1524)
				(type default)
			)
			(layer "F.SilkS")
		)
		(fp_line
			(start 1.7018 -1.100074)
			(end 1.7018 1.100074)
			(stroke
				(width 0.1524)
				(type default)
			)
			(layer "F.SilkS")
		)
		(fp_poly
			(pts
				(xy -2.339594 -0.650748) (xy -2.893314 -0.354076) (xy -2.893314 -0.978916)
			)
			(stroke
				(width 0)
				(type default)
			)
			(fill yes)
			(layer "F.SilkS")
		)
		(fp_line
			(start -0.670052 1.100074)
			(end -0.670052 0.8001)
			(stroke
				(width 0.1)
				(type default)
			)
			(layer "F.Fab")
		)
		(fp_line
			(start 0.670052 1.100074)
			(end -0.670052 1.100074)
			(stroke
				(width 0.1)
				(type default)
			)
			(layer "F.Fab")
		)
		(fp_line
			(start -1.100074 0.8001)
			(end -1.100074 -0.8001)
			(stroke
				(width 0.1)
				(type default)
			)
			(layer "F.Fab")
		)
		(fp_line
			(start -0.670052 0.8001)
			(end -1.100074 0.8001)
			(stroke
				(width 0.1)
				(type default)
			)
			(layer "F.Fab")
		)
		(fp_line
			(start -0.670052 0.8001)
			(end -0.670052 -0.8001)
			(stroke
				(width 0.1)
				(type default)
			)
			(layer "F.Fab")
		)
		(fp_line
			(start 0.670052 0.8001)
			(end 0.670052 1.100074)
			(stroke
				(width 0.1)
				(type default)
			)
			(layer "F.Fab")
		)
		(fp_line
			(start 1.100074 0.8001)
			(end 0.670052 0.8001)
			(stroke
				(width 0.1)
				(type default)
			)
			(layer "F.Fab")
		)
		(fp_line
			(start -1.100074 -0.8001)
			(end -0.670052 -0.8001)
			(stroke
				(width 0.1)
				(type default)
			)
			(layer "F.Fab")
		)
		(fp_line
			(start -0.670052 -0.8001)
			(end -0.670052 -1.100074)
			(stroke
				(width 0.1)
				(type default)
			)
			(layer "F.Fab")
		)
		(fp_line
			(start 0.670052 -0.8001)
			(end 0.670052 0.8001)
			(stroke
				(width 0.1)
				(type default)
			)
			(layer "F.Fab")
		)
		(fp_line
			(start 0.670052 -0.8001)
			(end 1.100074 -0.8001)
			(stroke
				(width 0.1)
				(type default)
			)
			(layer "F.Fab")
		)
		(fp_line
			(start 1.100074 -0.8001)
			(end 1.100074 0.8001)
			(stroke
				(width 0.1)
				(type default)
			)
			(layer "F.Fab")
		)
		(fp_line
			(start -0.670052 -1.100074)
			(end 0.670052 -1.100074)
			(stroke
				(width 0.1)
				(type default)
			)
			(layer "F.Fab")
		)
		(fp_line
			(start 0.670052 -1.100074)
			(end 0.670052 -0.8001)
			(stroke
				(width 0.1)
				(type default)
			)
			(layer "F.Fab")
		)
		(fp_poly
			(pts
				(xy -2.33172 -0.338328) (xy -2.33172 -0.963168) (xy -1.778 -0.635)
			)
			(stroke
				(width 0)
				(type default)
			)
			(fill yes)
			(layer "F.Fab")
		)
		(pad "1" smd rect
			(at -0.937514 -0.649986)
			(size 0.3048 1.2446)
			(layers "F.Cu" "F.Mask" "F.Paste")
			(net "GND")
		)
		(pad "2" smd rect
			(at -0.937514 0)
			(size 0.3048 1.2446)
			(layers "F.Cu" "F.Mask" "F.Paste")
			(net "PWRGD_P12V_MEM_CPU0_EN")
		)
		(pad "3" smd rect
			(at -0.937514 0.649986)
			(size 0.3048 1.2446)
			(layers "F.Cu" "F.Mask" "F.Paste")
			(net "PWRGD_P12V_MEM_CPU0")
		)
		(pad "4" smd rect
			(at 0.937514 0.649986)
			(size 0.3048 1.2446)
			(layers "F.Cu" "F.Mask" "F.Paste")
			(net "GND")
		)
		(pad "5" smd rect
			(at 0.937514 0)
			(size 0.3048 1.2446)
			(layers "F.Cu" "F.Mask" "F.Paste")
			(net "PWRGD_P12V_MEM_CPU0_EN_N")
		)
		(pad "6" smd rect
			(at 0.937514 -0.649986)
			(size 0.3048 1.2446)
			(layers "F.Cu" "F.Mask" "F.Paste")
			(net "PWRGD_P12V_MEM_CPU0_EN_N")
		)
	)
	(footprint ""
		(layer "F.Cu")
		(at 19.241516 -40.942514)
		(property "Reference" "R1307"
			(at 0 0 0)
			(layer "F.SilkS")
			(hide yes)
			(effects
				(font
					(size 1.27 1.27)
				)
			)
		)
		(property "Value" ""
			(at 0 0 0)
			(layer "F.Fab")
			(effects
				(font
					(size 1.27 1.27)
				)
			)
		)
		(duplicate_pad_numbers_are_jumpers no)
		(fp_line
			(start -0.7874 -0.4064)
			(end 0.7874 -0.4064)
			(stroke
				(width 0.1524)
				(type default)
			)
			(layer "F.SilkS")
		)
		(fp_line
			(start -0.7874 0.4064)
			(end -0.7874 -0.4064)
			(stroke
				(width 0.1524)
				(type default)
			)
			(layer "F.SilkS")
		)
		(fp_line
			(start 0.7874 -0.4064)
			(end 0.7874 0.4064)
			(stroke
				(width 0.1524)
				(type default)
			)
			(layer "F.SilkS")
		)
		(fp_line
			(start 0.7874 0.4064)
			(end -0.7874 0.4064)
			(stroke
				(width 0.1524)
				(type default)
			)
			(layer "F.SilkS")
		)
		(fp_line
			(start -0.67945 -0.305054)
			(end -0.12065 -0.305054)
			(stroke
				(width 0.1)
				(type default)
			)
			(layer "F.Fab")
		)
		(fp_line
			(start -0.67945 0.3048)
			(end -0.67945 -0.305054)
			(stroke
				(width 0.1)
				(type default)
			)
			(layer "F.Fab")
		)
		(fp_line
			(start -0.12065 -0.305054)
			(end -0.12065 -0.2794)
			(stroke
				(width 0.1)
				(type default)
			)
			(layer "F.Fab")
		)
		(fp_line
			(start -0.12065 -0.2794)
			(end 0.12065 -0.2794)
			(stroke
				(width 0.1)
				(type default)
			)
			(layer "F.Fab")
		)
		(fp_line
			(start -0.12065 0.2794)
			(end -0.12065 0.3048)
			(stroke
				(width 0.1)
				(type default)
			)
			(layer "F.Fab")
		)
		(fp_line
			(start -0.12065 0.3048)
			(end -0.67945 0.3048)
			(stroke
				(width 0.1)
				(type default)
			)
			(layer "F.Fab")
		)
		(fp_line
			(start 0.120396 0.2794)
			(end -0.12065 0.2794)
			(stroke
				(width 0.1)
				(type default)
			)
			(layer "F.Fab")
		)
		(fp_line
			(start 0.120396 0.3048)
			(end 0.120396 0.2794)
			(stroke
				(width 0.1)
				(type default)
			)
			(layer "F.Fab")
		)
		(fp_line
			(start 0.12065 -0.3048)
			(end 0.67945 -0.3048)
			(stroke
				(width 0.1)
				(type default)
			)
			(layer "F.Fab")
		)
		(fp_line
			(start 0.12065 -0.2794)
			(end 0.12065 -0.3048)
			(stroke
				(width 0.1)
				(type default)
			)
			(layer "F.Fab")
		)
		(fp_line
			(start 0.67945 -0.3048)
			(end 0.67945 0.3048)
			(stroke
				(width 0.1)
				(type default)
			)
			(layer "F.Fab")
		)
		(fp_line
			(start 0.67945 0.3048)
			(end 0.120396 0.3048)
			(stroke
				(width 0.1)
				(type default)
			)
			(layer "F.Fab")
		)
		(pad "1" smd circle
			(at -0.40005 0)
			(size 0 0)
			(layers "F.Cu" "F.Mask" "F.Paste")
			(net "GND")
		)
		(pad "2" smd circle
			(at 0.40005 0)
			(size 0 0)
			(layers "F.Cu" "F.Mask" "F.Paste")
			(net "INA230_7_A1")
		)
	)
	(footprint ""
		(layer "F.Cu")
		(at 312.725308 -43.46321)
		(property "Reference" "U269"
			(at -3.27914 -4.806188 0)
			(unlocked yes)
			(layer "F.SilkS")
			(effects
				(font
					(size 0.7874 0.5842)
					(thickness 0.1524)
				)
				(justify left)
			)
		)
		(property "Value" ""
			(at 0 0 0)
			(layer "F.Fab")
			(effects
				(font
					(size 1.27 1.27)
				)
			)
		)
		(duplicate_pad_numbers_are_jumpers no)
		(fp_line
			(start -1.868932 -2.549906)
			(end -1.868932 2.549906)
			(stroke
				(width 0.1524)
				(type default)
			)
			(layer "F.SilkS")
		)
		(fp_line
			(start -1.868932 2.549906)
			(end 1.868932 2.549906)
			(stroke
				(width 0.1524)
				(type default)
			)
			(layer "F.SilkS")
		)
		(fp_line
			(start -1.025906 -2.549906)
			(end -1.868932 -2.549906)
			(stroke
				(width 0.1524)
				(type default)
			)
			(layer "F.SilkS")
		)
		(fp_line
			(start 0 -1.524)
			(end -1.025906 -2.549906)
			(stroke
				(width 0.1524)
				(type default)
			)
			(layer "F.SilkS")
		)
		(fp_line
			(start 1.025906 -2.549906)
			(end 0 -1.524)
			(stroke
				(width 0.1524)
				(type default)
			)
			(layer "F.SilkS")
		)
		(fp_line
			(start 1.868932 -2.549906)
			(end 1.025906 -2.549906)
			(stroke
				(width 0.1524)
				(type default)
			)
			(layer "F.SilkS")
		)
		(fp_line
			(start 1.868932 2.549906)
			(end 1.868932 -2.549906)
			(stroke
				(width 0.1524)
				(type default)
			)
			(layer "F.SilkS")
		)
		(fp_poly
			(pts
				(xy -3.243326 -3.828796) (xy -2.227326 -3.828796) (xy -2.735326 -2.812796)
			)
			(stroke
				(width 0)
				(type default)
			)
			(fill yes)
			(layer "F.SilkS")
		)
		(fp_line
			(start -2.249932 -2.549906)
			(end -2.249932 2.549906)
			(stroke
				(width 0.1)
				(type default)
			)
			(layer "F.Fab")
		)
		(fp_line
			(start -2.249932 2.549906)
			(end 2.249932 2.549906)
			(stroke
				(width 0.1)
				(type default)
			)
			(layer "F.Fab")
		)
		(fp_line
			(start 2.249932 -2.549906)
			(end -2.249932 -2.549906)
			(stroke
				(width 0.1)
				(type default)
			)
			(layer "F.Fab")
		)
		(fp_line
			(start 2.249932 2.549906)
			(end 2.249932 -2.549906)
			(stroke
				(width 0.1)
				(type default)
			)
			(layer "F.Fab")
		)
		(fp_poly
			(pts
				(xy -4.7752 -1.787398) (xy -4.7752 -2.803398) (xy -3.7592 -2.295398)
			)
			(stroke
				(width 0)
				(type default)
			)
			(fill yes)
			(layer "F.Fab")
		)
		(pad "1" smd rect
			(at -2.800096 -2.275078 270)
			(size 0.3556 1.6002)
			(layers "F.Cu" "F.Mask" "F.Paste")
			(net "ADC128_VREF")
		)
		(pad "2" smd rect
			(at -2.800096 -1.625092 270)
			(size 0.3556 1.6002)
			(layers "F.Cu" "F.Mask" "F.Paste")
			(net "SMB_SEN_TIC_3V3AUX_SDA")
		)
		(pad "3" smd rect
			(at -2.800096 -0.975106 270)
			(size 0.3556 1.6002)
			(layers "F.Cu" "F.Mask" "F.Paste")
			(net "SMB_SEN_TIC_3V3AUX_SCL")
		)
		(pad "4" smd rect
			(at -2.800096 -0.32512 270)
			(size 0.3556 1.6002)
			(layers "F.Cu" "F.Mask" "F.Paste")
			(net "GND")
		)
		(pad "5" smd rect
			(at -2.800096 0.32512 270)
			(size 0.3556 1.6002)
			(layers "F.Cu" "F.Mask" "F.Paste")
			(net "P3V3_ADC128_VCC")
		)
		(pad "6" smd rect
			(at -2.800096 0.975106 270)
			(size 0.3556 1.6002)
			(layers "F.Cu" "F.Mask" "F.Paste")
			(net "TP_ADC128_INT")
		)
		(pad "7" smd rect
			(at -2.800096 1.625092 270)
			(size 0.3556 1.6002)
			(layers "F.Cu" "F.Mask" "F.Paste")
			(net "ADC128_A0")
		)
		(pad "8" smd rect
			(at -2.800096 2.275078 270)
			(size 0.3556 1.6002)
			(layers "F.Cu" "F.Mask" "F.Paste")
			(net "ADC128_A1")
		)
		(pad "9" smd rect
			(at 2.800096 2.275078 270)
			(size 0.3556 1.6002)
			(layers "F.Cu" "F.Mask" "F.Paste")
			(net "P12V_E1S_0_ISENSE_TIC")
		)
		(pad "10" smd rect
			(at 2.800096 1.625092 270)
			(size 0.3556 1.6002)
			(layers "F.Cu" "F.Mask" "F.Paste")
			(net "P3V3_PDB_AUX_ADC_TIC")
		)
		(pad "11" smd rect
			(at 2.800096 0.975106 270)
			(size 0.3556 1.6002)
			(layers "F.Cu" "F.Mask" "F.Paste")
			(net "P3V3_AUX_ADC_TIC")
		)
		(pad "12" smd rect
			(at 2.800096 0.32512 270)
			(size 0.3556 1.6002)
			(layers "F.Cu" "F.Mask" "F.Paste")
			(net "P3V3_ADC_TIC")
		)
		(pad "13" smd rect
			(at 2.800096 -0.32512 270)
			(size 0.3556 1.6002)
			(layers "F.Cu" "F.Mask" "F.Paste")
			(net "P5V_ADC_TIC")
		)
		(pad "14" smd rect
			(at 2.800096 -0.975106 270)
			(size 0.3556 1.6002)
			(layers "F.Cu" "F.Mask" "F.Paste")
			(net "P12V_OCP_V3_2_ISENSE_TIC")
		)
		(pad "15" smd rect
			(at 2.800096 -1.625092 270)
			(size 0.3556 1.6002)
			(layers "F.Cu" "F.Mask" "F.Paste")
			(net "P12V_OCP_SFF_ISENSE_TIC")
		)
		(pad "16" smd rect
			(at 2.800096 -2.275078 270)
			(size 0.3556 1.6002)
			(layers "F.Cu" "F.Mask" "F.Paste")
			(net "P12V_AUX_ADC_TIC")
		)
	)
	(footprint ""
		(layer "F.Cu")
		(at 103.5304 -396.6972 90)
		(property "Reference" "R672"
			(at 0 0 90)
			(layer "F.SilkS")
			(hide yes)
			(effects
				(font
					(size 1.27 1.27)
				)
			)
		)
		(property "Value" ""
			(at 0 0 90)
			(layer "F.Fab")
			(effects
				(font
					(size 1.27 1.27)
				)
			)
		)
		(duplicate_pad_numbers_are_jumpers no)
		(fp_line
			(start 0.32512 -0.175006)
			(end 0.32512 0.175006)
			(stroke
				(width 0.1)
				(type default)
			)
			(layer "F.Fab")
		)
		(fp_line
			(start -0.32512 -0.175006)
			(end 0.32512 -0.175006)
			(stroke
				(width 0.1)
				(type default)
			)
			(layer "F.Fab")
		)
		(fp_line
			(start 0.32512 0.175006)
			(end -0.32512 0.175006)
			(stroke
				(width 0.1)
				(type default)
			)
			(layer "F.Fab")
		)
		(fp_line
			(start -0.32512 0.175006)
			(end -0.32512 -0.175006)
			(stroke
				(width 0.1)
				(type default)
			)
			(layer "F.Fab")
		)
		(pad "1" smd rect
			(at -0.2667 0 90)
			(size 0.3048 0.381)
			(layers "F.Cu" "F.Mask" "F.Paste")
			(net "SMB_RT_CPU1_P0_ROM_R_SCL")
		)
		(pad "2" smd rect
			(at 0.2667 0 270)
			(size 0.3048 0.381)
			(layers "F.Cu" "F.Mask" "F.Paste")
			(net "SMB_RT_CPU1_P0_ROM_SCL")
		)
	)
	(footprint ""
		(layer "F.Cu")
		(at 244.2972 -287.376362)
		(property "Reference" "PC6901"
			(at 0 0 0)
			(layer "F.SilkS")
			(hide yes)
			(effects
				(font
					(size 1.27 1.27)
				)
			)
		)
		(property "Value" ""
			(at 0 0 0)
			(layer "F.Fab")
			(effects
				(font
					(size 1.27 1.27)
				)
			)
		)
		(duplicate_pad_numbers_are_jumpers no)
		(fp_line
			(start -1.524 -0.762)
			(end 1.524 -0.762)
			(stroke
				(width 0.1524)
				(type default)
			)
			(layer "F.SilkS")
		)
		(fp_line
			(start -1.524 0.762)
			(end -1.524 -0.762)
			(stroke
				(width 0.1524)
				(type default)
			)
			(layer "F.SilkS")
		)
		(fp_line
			(start 1.524 -0.762)
			(end 1.524 0.762)
			(stroke
				(width 0.1524)
				(type default)
			)
			(layer "F.SilkS")
		)
		(fp_line
			(start 1.524 0.762)
			(end -1.524 0.762)
			(stroke
				(width 0.1524)
				(type default)
			)
			(layer "F.SilkS")
		)
		(fp_line
			(start -1.1049 -0.724916)
			(end -1.1049 0.724916)
			(stroke
				(width 0.1)
				(type default)
			)
			(layer "F.Fab")
		)
		(fp_line
			(start -1.1049 0.724916)
			(end 1.1049 0.724916)
			(stroke
				(width 0.1)
				(type default)
			)
			(layer "F.Fab")
		)
		(fp_line
			(start 1.1049 -0.724916)
			(end -1.1049 -0.724916)
			(stroke
				(width 0.1)
				(type default)
			)
			(layer "F.Fab")
		)
		(fp_line
			(start 1.1049 0.724916)
			(end 1.1049 -0.724916)
			(stroke
				(width 0.1)
				(type default)
			)
			(layer "F.Fab")
		)
		(pad "1" smd rect
			(at -0.889 0 180)
			(size 1.016 1.27)
			(layers "F.Cu" "F.Mask" "F.Paste")
			(net "SW_P12V_AUX_P1V8_RETIMER_CPU0_FLT")
		)
		(pad "2" smd rect
			(at 0.889 0 180)
			(size 1.016 1.27)
			(layers "F.Cu" "F.Mask" "F.Paste")
			(net "GND")
		)
	)
)
